# T6G (Grand Teton) — schematic parts with pin connectivity, parts 8081–8081 of 8303; source: Cadence DE-HDL packaged netlist (pstxprt.dat, pstxnet.dat, pstchip.dat)

U25  GENOA_SP5  SOCKET6096_13568-001 IO  pkg SOCKET6096_93-4X120-45XA  page 10  (pins 2689-3024 of 6096)
  BY32  VDDCR_CPU1_BY32  POWER  = PVDDCR_CPU1_P0
  BY33  VDDCR_CPU1_BY33  POWER  = PVDDCR_CPU1_P0
  BY34  VSS_BY34  POWER  = GND
  BY35  P2_TXN3  OUT  = P5E_CPU0_P2_TX_DN<3>
  BY36  P2_TXP3  OUT  = P5E_CPU0_P2_TX_DP<3>
  BY37  VSS_BY37  POWER  = GND
  BY39  VSS_BY39  POWER  = GND
  BY40  \p0_rxp12||sata14_rxp\  IN  = P5E_CPU0_P0_RX_DP<12>
  BY41  \p0_rxn12||sata14_rxn\  IN  = P5E_CPU0_P0_RX_DN<12>
  BY42  VSS_BY42  POWER  = GND
  BY43  VDDCR_CPU1_BY43  POWER  = PVDDCR_CPU1_P0
  BY44  VDDCR_CPU1_BY44  POWER  = PVDDCR_CPU1_P0
  BY45  VSS_BY45  POWER  = GND
  BY46  VDDCR_CPU1_BY46  POWER  = PVDDCR_CPU1_P0
  BY47  VDDCR_CPU1_BY47  POWER  = PVDDCR_CPU1_P0
  BY48  VSS_BY48  POWER  = GND
  BY49  VDDCR_CPU1_BY49  POWER  = PVDDCR_CPU1_P0
  BY50  VDDCR_CPU1_BY50  POWER  = PVDDCR_CPU1_P0
  BY51  VSS_BY51  POWER  = GND
  BY52  VDDCR_CPU1_BY52  POWER  = PVDDCR_CPU1_P0
  BY53  VDDCR_CPU1_BY53  POWER  = PVDDCR_CPU1_P0
  BY54  VSS_BY54  POWER  = GND
  BY55  MCB_DQS_H4  BI  = M_C_CPU0_SB_DQS_DP<4>
  BY56  MCB_CHECK0  BI  = M_C_CPU0_SB_CB<0>
  BY57  VSS_BY57  POWER  = GND
  BY58  MDB_DQS_H4  BI  = M_D_CPU0_SB_DQS_DP<4>
  BY59  VSS_BY59  POWER  = GND
  BY60  MDB_CHECK0  BI  = M_D_CPU0_SB_CB<0>
  BY61  VSS_BY61  POWER  = GND
  BY62  MBB_DQS_H4  BI  = M_B_CPU0_SB_DQS_DP<4>
  BY63  MBB_CHECK0  BI  = M_B_CPU0_SB_CB<0>
  BY64  VSS_BY64  POWER  = GND
  BY65  MFB_DQS_H4  BI  = M_F_CPU0_SB_DQS_DP<4>
  BY66  VSS_BY66  POWER  = GND
  BY67  MFB_CHECK0  BI  = M_F_CPU0_SB_CB<0>
  BY68  VSS_BY68  POWER  = GND
  BY69  MEB_DQS_H4  BI  = M_E_CPU0_SB_DQS_DP<4>
  BY70  MEB_CHECK0  BI  = M_E_CPU0_SB_CB<0>
  BY71  VSS_BY71  POWER  = GND
  BY72  MAB_DQS_H4  BI  = M_A_CPU0_SB_DQS_DP<4>
  BY73  VSS_BY73  POWER  = GND
  BY74  MAB_CHECK0  BI  = M_A_CPU0_SB_CB<0>
  C1  VSS_C1  POWER  = GND
  C2  VDDCR_CPU0_SENSE  POWER  = VSENSE_PVDDCR_CPU0_P0_DP
  C3  VSS_SENSE_A  POWER  = VSENSE_VSS_SENSE_A_P0
  C4  VDDCR_SOC_C4  POWER  = PVDDCR_SOC_P0
  C5  VSS_C5  POWER  = GND
  C6  GPP_CLK02N  OUT  = CLK_100M_CPU0_CLK02_R_DN
  C7  \i3c1_scl||i2c1_scl||spd1_scl||agpio147\  BI  = I3C_1_SPD_DDRGL_CPU0_R_SCL
  C8  VSS_C8  POWER  = GND
  C9  GPP_CLK05N  OUT  = CLK_100M_CPU0_CLK05_R_DN
  C10  VSS_C10  POWER  = GND
  C11  VSS_C11  POWER  = GND
  C12  GPP_CLK04N  OUT  = CLK_100M_CPU0_CLK04_R_DN
  C13  VSS_C13  POWER  = GND
  C14  \agpio257||sgpio1_clk||clk_req01_l\  BI  = FAB_REV_ID1
  C15  VSS_C15  POWER  = GND
  C16  DBREQ_L  IN  = JTAG_CPU0_DBREQ_N
  C17  TDI  IN  = JTAG_CPU0_TDI
  C18  TDO  OUT  = JTAG_CPU0_R_TDO
  C19  SP5R1  OUT  = CPU0_SP5R1
  C20  VDDCR_CPU0_C20  POWER  = PVDDCR_CPU0_P0
  C21  VSS_C21  POWER  = GND
  C22  PCC0_L  IN  = FM_P0_PCC0_N
  C23  TEST4_CCD15  TRI  = NC
  C24  VSS_C24  POWER  = GND
  C25  USB00_TXP  OUT  = USB3_CPU0_BMC_TX_DP
  C26  USB00_TXN  OUT  = USB3_CPU0_BMC_TX_DN
  C27  VSS_C27  POWER  = GND
  C28  USB01_RXN  IN  = NC
  C29  USB01_RXP  IN  = NC
  C30  VSS_C30  POWER  = GND
  C31  RSVD_C31  TRI  = NC
  C32  AZ_BITCLK  OUT  = NC_CPU0_AZ_BITCLK
  C33  \az_sdin0||sw_mdata3\  OUT  = NC_CPU0_AZ_SDIN0
  C34  RSVD_C34  TRI  = NC
  C35  RSVD_C35  TRI  = NC
  C36  VSS_C36  POWER  = GND
  C40  VSS_C40  POWER  = GND
  C41  P5_TXP3  OUT  = NC
  C42  P5_TXN3  OUT  = NC
  C43  VSS_C43  POWER  = GND
  C44  P5_TXP2  OUT  = P2E_CPU0_P5_TX_DP
  C45  P5_TXN2  OUT  = P2E_CPU0_P5_TX_DN
  C46  VSS_C46  POWER  = GND
  C47  \wafl_txp1||p5_txp1\  OUT  = NC
  C48  \wafl_txn1||p5_txn1\  OUT  = NC
  C49  VSS_C49  POWER  = GND
  C50  \wafl_txp0||p5_txp0\  OUT  = WAFL_CPU0_TX0_CPU1_RX1_DP
  C51  \wafl_txn0||p5_txn0\  OUT  = WAFL_CPU0_TX0_CPU1_RX1_DN
  C52  VSS_C52  POWER  = GND
  C53  RSVD_C53  TRI  = NC
  C54  RSVD_C54  TRI  = NC
  C55  VSS_C55  POWER  = GND
  C56  VSS_C56  POWER  = GND
  C57  VSS_C57  POWER  = GND
  C58  TEST4_CCD12  TRI  = NC
  C59  TEST5_CCD12  TRI  = NC
  C60  TEST40  OUT  = TP_M_A_CPU0_SA_TEST40
  C61  VSS_C61  POWER  = GND
  C62  BP1  OUT  = CPU0_BP1
  C63  BP0  OUT  = CPU0_BP0
  C64  VSS_C64  POWER  = GND
  C65  XTRIG_L5  OUT  = CPU0_XTRIG_R2_L5
  C66  XTRIG_L4  OUT  = CPU0_XTRIG_R2_L4
  C67  VSS_C67  POWER  = GND
  C68  SP5R2  OUT  = CPU0_SP5R2
  C69  VSS_C69  POWER  = GND
  C70  CORETYPE0  OUT  = CPU0_CORETYPE0
  C71  VSS_C71  POWER  = GND
  C72  \i3c2_scl||i2c2_scl||spd2_scl||agpio149\  BI  = SMB_CPU0_2_R_SCL
  C73  VSS_C73  POWER  = GND
  C74  VDD_18_S5_SENSE  POWER  = VSENSE_PVDD18_S5_P0_DP
  C75  VSS_C75  POWER  = GND
  CA1  VSS_CA1  POWER  = GND
  CA2  MGB_CHECK2  BI  = M_G_CPU0_SB_CB<2>
  CA3  MGB_CHECK1  BI  = M_G_CPU0_SB_CB<1>
  CA4  VDD_11_S3_CA4  POWER  = PVDD11_S3_P0
  CA5  MKB_CHECK2  BI  = M_K_CPU0_SB_CB<2>
  CA6  VSS_CA6  POWER  = GND
  CA7  MKB_CHECK1  BI  = M_K_CPU0_SB_CB<1>
  CA8  VSS_CA8  POWER  = GND
  CA9  MLB_CHECK2  BI  = M_L_CPU0_SB_CB<2>
  CA10  MLB_CHECK1  BI  = M_L_CPU0_SB_CB<1>
  CA11  VDD_11_S3_CA11  POWER  = PVDD11_S3_P0
  CA12  MHB_CHECK2  BI  = M_H_CPU0_SB_CB<2>
  CA13  VSS_CA13  POWER  = GND
  CA14  MHB_CHECK1  BI  = M_H_CPU0_SB_CB<1>
  CA15  VSS_CA15  POWER  = GND
  CA16  MJB_CHECK2  BI  = M_J_CPU0_SB_CB<2>
  CA17  MJB_CHECK1  BI  = M_J_CPU0_SB_CB<1>
  CA18  VDD_11_S3_CA18  POWER  = PVDD11_S3_P0
  CA19  MIB_CHECK2  BI  = M_I_CPU0_SB_CB<2>
  CA20  VSS_CA20  POWER  = GND
  CA21  MIB_CHECK1  BI  = M_I_CPU0_SB_CB<1>
  CA22  VSS_CA22  POWER  = GND
  CA23  P2_TXN14  OUT  = P5E_CPU0_P2_TX_DN<14>
  CA24  P2_TXP14  OUT  = P5E_CPU0_P2_TX_DP<14>
  CA25  VSS_CA25  POWER  = GND
  CA26  P2_TXN11  OUT  = P5E_CPU0_P2_TX_DN<11>
  CA27  P2_TXP11  OUT  = P5E_CPU0_P2_TX_DP<11>
  CA28  VSS_CA28  POWER  = GND
  CA29  P2_TXN8  OUT  = P5E_CPU0_P2_TX_DN<8>
  CA30  P2_TXP8  OUT  = P5E_CPU0_P2_TX_DP<8>
  CA31  VSS_CA31  POWER  = GND
  CA32  P2_TXN5  OUT  = P5E_CPU0_P2_TX_DN<5>
  CA33  P2_TXP5  OUT  = P5E_CPU0_P2_TX_DP<5>
  CA34  VSS_CA34  POWER  = GND
  CA35  VSS_CA35  POWER  = GND
  CA36  VSS_CA36  POWER  = GND
  CA40  VSS_CA40  POWER  = GND
  CA41  VSS_CA41  POWER  = GND
  CA42  VSS_CA42  POWER  = GND
  CA43  \p0_rxp10||sata12_rxp\  IN  = P5E_CPU0_P0_RX_DP<10>
  CA44  \p0_rxn10||sata12_rxn\  IN  = P5E_CPU0_P0_RX_DN<10>
  CA45  VSS_CA45  POWER  = GND
  CA46  \p0_rxp7||sata07_rxp\  IN  = P5E_CPU0_P0_RX_DP<7>
  CA47  \p0_rxn7||sata07_rxn\  IN  = P5E_CPU0_P0_RX_DN<7>
  CA48  VSS_CA48  POWER  = GND
  CA49  \p0_rxp4||sata04_rxp\  IN  = P5E_CPU0_P0_RX_DP<4>
  CA50  \p0_rxn4||sata04_rxn\  IN  = P5E_CPU0_P0_RX_DN<4>
  CA51  VSS_CA51  POWER  = GND
  CA52  \p0_rxp1||sata01_rxp\  IN  = P5E_CPU0_P0_RX_DP<1>
  CA53  \p0_rxn1||sata01_rxn\  IN  = P5E_CPU0_P0_RX_DN<1>
  CA54  VSS_CA54  POWER  = GND
  CA55  MCB_CHECK1  BI  = M_C_CPU0_SB_CB<1>
  CA56  VSS_CA56  POWER  = GND
  CA57  MCB_CHECK2  BI  = M_C_CPU0_SB_CB<2>
  CA58  VDDIO_CA58  POWER  = PVDDIO_P0
  CA59  MDB_CHECK1  BI  = M_D_CPU0_SB_CB<1>
  CA60  MDB_CHECK2  BI  = M_D_CPU0_SB_CB<2>
  CA61  VSS_CA61  POWER  = GND
  CA62  MBB_CHECK1  BI  = M_B_CPU0_SB_CB<1>
  CA63  VSS_CA63  POWER  = GND
  CA64  MBB_CHECK2  BI  = M_B_CPU0_SB_CB<2>
  CA65  VDDIO_CA65  POWER  = PVDDIO_P0
  CA66  MFB_CHECK1  BI  = M_F_CPU0_SB_CB<1>
  CA67  MFB_CHECK2  BI  = M_F_CPU0_SB_CB<2>
  CA68  VSS_CA68  POWER  = GND
  CA69  MEB_CHECK1  BI  = M_E_CPU0_SB_CB<1>
  CA70  VSS_CA70  POWER  = GND
  CA71  MEB_CHECK2  BI  = M_E_CPU0_SB_CB<2>
  CA72  VDDIO_CA72  POWER  = PVDDIO_P0
  CA73  MAB_CHECK1  BI  = M_A_CPU0_SB_CB<1>
  CA74  MAB_CHECK2  BI  = M_A_CPU0_SB_CB<2>
  CA75  VSS_CA75  POWER  = GND
  CB2  MGB_DATA0  BI  = M_G_CPU0_SB_DQ<0>
  CB3  VSS_CB3  POWER  = GND
  CB4  MGB_CHECK3  BI  = M_G_CPU0_SB_CB<3>
  CB5  VSS_CB5  POWER  = GND
  CB6  MKB_DATA0  BI  = M_K_CPU0_SB_DQ<0>
  CB7  MKB_CHECK3  BI  = M_K_CPU0_SB_CB<3>
  CB8  VSS_CB8  POWER  = GND
  CB9  MLB_DATA0  BI  = M_L_CPU0_SB_DQ<0>
  CB10  VSS_CB10  POWER  = GND
  CB11  MLB_CHECK3  BI  = M_L_CPU0_SB_CB<3>
  CB12  VSS_CB12  POWER  = GND
  CB13  MHB_DATA0  BI  = M_H_CPU0_SB_DQ<0>
  CB14  MHB_CHECK3  BI  = M_H_CPU0_SB_CB<3>
  CB15  VSS_CB15  POWER  = GND
  CB16  MJB_DATA0  BI  = M_J_CPU0_SB_DQ<0>
  CB17  VSS_CB17  POWER  = GND
  CB18  MJB_CHECK3  BI  = M_J_CPU0_SB_CB<3>
  CB19  VSS_CB19  POWER  = GND
  CB20  MIB_DATA0  BI  = M_I_CPU0_SB_DQ<0>
  CB21  MIB_CHECK3  BI  = M_I_CPU0_SB_CB<3>
  CB22  VDD_11_S3_CB22  POWER  = PVDD11_S3_P0
  CB23  VSS_CB23  POWER  = GND
  CB24  VSS_CB24  POWER  = GND
  CB25  VSS_CB25  POWER  = GND
  CB26  VSS_CB26  POWER  = GND
  CB27  VSS_CB27  POWER  = GND
  CB28  VSS_CB28  POWER  = GND
  CB29  VSS_CB29  POWER  = GND
  CB30  VSS_CB30  POWER  = GND
  CB31  VSS_CB31  POWER  = GND
  CB32  VSS_CB32  POWER  = GND
  CB33  VSS_CB33  POWER  = GND
  CB34  VSS_CB34  POWER  = GND
  CB35  P2_TXN2  OUT  = P5E_CPU0_P2_TX_DN<2>
  CB36  P2_TXP2  OUT  = P5E_CPU0_P2_TX_DP<2>
  CB37  VSS_CB37  POWER  = GND
  CB39  VSS_CB39  POWER  = GND
  CB40  \p0_rxp13||sata15_rxp\  IN  = P5E_CPU0_P0_RX_DP<13>
  CB41  \p0_rxn13||sata15_rxn\  IN  = P5E_CPU0_P0_RX_DN<13>
  CB42  VSS_CB42  POWER  = GND
  CB43  VSS_CB43  POWER  = GND
  CB44  VSS_CB44  POWER  = GND
  CB45  VSS_CB45  POWER  = GND
  CB46  VSS_CB46  POWER  = GND
  CB47  VSS_CB47  POWER  = GND
  CB48  VSS_CB48  POWER  = GND
  CB49  VSS_CB49  POWER  = GND
  CB50  VSS_CB50  POWER  = GND
  CB51  VSS_CB51  POWER  = GND
  CB52  VSS_CB52  POWER  = GND
  CB53  VSS_CB53  POWER  = GND
  CB54  VDDIO_CB54  POWER  = PVDDIO_P0
  CB55  MCB_CHECK3  BI  = M_C_CPU0_SB_CB<3>
  CB56  MCB_DATA0  BI  = M_C_CPU0_SB_DQ<0>
  CB57  VSS_CB57  POWER  = GND
  CB58  MDB_CHECK3  BI  = M_D_CPU0_SB_CB<3>
  CB59  VSS_CB59  POWER  = GND
  CB60  MDB_DATA0  BI  = M_D_CPU0_SB_DQ<0>
  CB61  VSS_CB61  POWER  = GND
  CB62  MBB_CHECK3  BI  = M_B_CPU0_SB_CB<3>
  CB63  MBB_DATA0  BI  = M_B_CPU0_SB_DQ<0>
  CB64  VSS_CB64  POWER  = GND
  CB65  MFB_CHECK3  BI  = M_F_CPU0_SB_CB<3>
  CB66  VSS_CB66  POWER  = GND
  CB67  MFB_DATA0  BI  = M_F_CPU0_SB_DQ<0>
  CB68  VSS_CB68  POWER  = GND
  CB69  MEB_CHECK3  BI  = M_E_CPU0_SB_CB<3>
  CB70  MEB_DATA0  BI  = M_E_CPU0_SB_DQ<0>
  CB71  VSS_CB71  POWER  = GND
  CB72  MAB_CHECK3  BI  = M_A_CPU0_SB_CB<3>
  CB73  VSS_CB73  POWER  = GND
  CB74  MAB_DATA0  BI  = M_A_CPU0_SB_DQ<0>
  CC1  VSS_CC1  POWER  = GND
  CC2  MGB_DATA2  BI  = M_G_CPU0_SB_DQ<2>
  CC3  MGB_DATA1  BI  = M_G_CPU0_SB_DQ<1>
  CC4  VSS_CC4  POWER  = GND
  CC5  MKB_DATA2  BI  = M_K_CPU0_SB_DQ<2>
  CC6  VSS_CC6  POWER  = GND
  CC7  MKB_DATA1  BI  = M_K_CPU0_SB_DQ<1>
  CC8  VSS_CC8  POWER  = GND
  CC9  MLB_DATA2  BI  = M_L_CPU0_SB_DQ<2>
  CC10  MLB_DATA1  BI  = M_L_CPU0_SB_DQ<1>
  CC11  VSS_CC11  POWER  = GND
  CC12  MHB_DATA2  BI  = M_H_CPU0_SB_DQ<2>
  CC13  VSS_CC13  POWER  = GND
  CC14  MHB_DATA1  BI  = M_H_CPU0_SB_DQ<1>
  CC15  VSS_CC15  POWER  = GND
  CC16  MJB_DATA2  BI  = M_J_CPU0_SB_DQ<2>
  CC17  MJB_DATA1  BI  = M_J_CPU0_SB_DQ<1>
  CC18  VSS_CC18  POWER  = GND
  CC19  MIB_DATA2  BI  = M_I_CPU0_SB_DQ<2>
  CC20  VSS_CC20  POWER  = GND
  CC21  MIB_DATA1  BI  = M_I_CPU0_SB_DQ<1>
  CC22  VSS_CC22  POWER  = GND
  CC23  P3_TXN13  OUT  = P5E_CPU0_P3_TX_DN<13>
  CC24  P3_TXP13  OUT  = P5E_CPU0_P3_TX_DP<13>
  CC25  VSS_CC25  POWER  = GND
  CC26  P3_TXN10  OUT  = P5E_CPU0_P3_TX_DN<10>
  CC27  P3_TXP10  OUT  = P5E_CPU0_P3_TX_DP<10>
  CC28  VSS_CC28  POWER  = GND
  CC29  P3_TXN7  OUT  = P5E_CPU0_P3_TX_DN<7>
  CC30  P3_TXP7  OUT  = P5E_CPU0_P3_TX_DP<7>
  CC31  VSS_CC31  POWER  = GND
  CC32  P3_TXN3  OUT  = P5E_CPU0_P3_TX_DN<3>
  CC33  P3_TXP3  OUT  = P5E_CPU0_P3_TX_DP<3>
  CC34  VSS_CC34  POWER  = GND
  CC35  VDDCR_CPU1_CC35  POWER  = PVDDCR_CPU1_P0
  CC36  VDDCR_CPU1_CC36  POWER  = PVDDCR_CPU1_P0
  CC40  VDDCR_CPU1_CC40  POWER  = PVDDCR_CPU1_P0
  CC41  VDDCR_CPU1_CC41  POWER  = PVDDCR_CPU1_P0
  CC42  VSS_CC42  POWER  = GND
  CC43  P1_RXP12  IN  = P5E_CPU0_P1_RX_DP<12>
  CC44  P1_RXN12  IN  = P5E_CPU0_P1_RX_DN<12>
  CC45  VSS_CC45  POWER  = GND
  CC46  P1_RXP8  IN  = P5E_CPU0_P1_RX_DP<8>
  CC47  P1_RXN8  IN  = P5E_CPU0_P1_RX_DN<8>
  CC48  VSS_CC48  POWER  = GND
  CC49  P1_RXP5  IN  = P5E_CPU0_P1_RX_DP<5>
  CC50  P1_RXN5  IN  = P5E_CPU0_P1_RX_DN<5>
  CC51  VSS_CC51  POWER  = GND
  CC52  P1_RXP2  IN  = P5E_CPU0_P1_RX_DP<2>
  CC53  P1_RXN2  IN  = P5E_CPU0_P1_RX_DN<2>
  CC54  VSS_CC54  POWER  = GND
  CC55  MCB_DATA1  BI  = M_C_CPU0_SB_DQ<1>
  CC56  VSS_CC56  POWER  = GND
  CC57  MCB_DATA2  BI  = M_C_CPU0_SB_DQ<2>
  CC58  VSS_CC58  POWER  = GND
  CC59  MDB_DATA1  BI  = M_D_CPU0_SB_DQ<1>
  CC60  MDB_DATA2  BI  = M_D_CPU0_SB_DQ<2>
  CC61  VSS_CC61  POWER  = GND
  CC62  MBB_DATA1  BI  = M_B_CPU0_SB_DQ<1>
  CC63  VSS_CC63  POWER  = GND
  CC64  MBB_DATA2  BI  = M_B_CPU0_SB_DQ<2>
  CC65  VSS_CC65  POWER  = GND
  CC66  MFB_DATA1  BI  = M_F_CPU0_SB_DQ<1>
  CC67  MFB_DATA2  BI  = M_F_CPU0_SB_DQ<2>
  CC68  VSS_CC68  POWER  = GND
  CC69  MEB_DATA1  BI  = M_E_CPU0_SB_DQ<1>
  CC70  VSS_CC70  POWER  = GND
  CC71  MEB_DATA2  BI  = M_E_CPU0_SB_DQ<2>
  CC72  VSS_CC72  POWER  = GND
  CC73  MAB_DATA1  BI  = M_A_CPU0_SB_DQ<1>
  CC74  MAB_DATA2  BI  = M_A_CPU0_SB_DQ<2>
  CC75  VSS_CC75  POWER  = GND
  CD2  MGB_DQS_H0  BI  = M_G_CPU0_SB_DQS_DP<0>
  CD3  VSS_CD3  POWER  = GND
  CD4  MGB_DATA3  BI  = M_G_CPU0_SB_DQ<3>
  CD5  VDD_11_S3_CD5  POWER  = PVDD11_S3_P0
  CD6  MKB_DQS_H0  BI  = M_K_CPU0_SB_DQS_DP<0>
  CD7  MKB_DATA3  BI  = M_K_CPU0_SB_DQ<3>
